(kicad_pcb
	(version 20241229)
	(generator "pcbnew")
	(generator_version "9.0")
	(general
		(thickness 1.62)
		(legacy_teardrops no)
	)
	(paper "A3")
	(title_block
		(title "COM Express 7 Baseboard")
		(date "2025-02-04")
		(rev "1.1.2")
		(company "Antmicro Ltd")
		(comment 1 "www.antmicro.com")
		(comment 9 "footprints 1-5 of 802")
	)
	(layers
		(0 "F.Cu" signal)
		(4 "In1.Cu" signal)
		(6 "In2.Cu" signal)
		(8 "In3.Cu" signal)
		(10 "In4.Cu" signal)
		(12 "In5.Cu" signal)
		(14 "In6.Cu" signal)
		(2 "B.Cu" signal)
		(9 "F.Adhes" user "F.Adhesive")
		(11 "B.Adhes" user "B.Adhesive")
		(13 "F.Paste" user)
		(15 "B.Paste" user)
		(5 "F.SilkS" user "F.Silkscreen")
		(7 "B.SilkS" user "B.Silkscreen")
		(1 "F.Mask" user)
		(3 "B.Mask" user)
		(17 "Dwgs.User" user "User.Drawings")
		(19 "Cmts.User" user "User.Comments")
		(21 "Eco1.User" user "User.Eco1")
		(23 "Eco2.User" user "User.Eco2")
		(25 "Edge.Cuts" user)
		(27 "Margin" user)
		(31 "F.CrtYd" user "F.Courtyard")
		(29 "B.CrtYd" user "B.Courtyard")
		(35 "F.Fab" user)
		(33 "B.Fab" user)
	)
	(footprint "antmicro-footprints:R_0402_1005Metric"
		(layer "F.Cu")
		(at 197.70861 77.152163 90)
		(descr "Resistor SMD 0402")
		(tags "resistor SMD 0402")
		(property "Reference" "R320"
			(at -1.9 -0.5 90)
			(layer "F.SilkS")
			(effects
				(font
					(size 0.7 0.7)
					(thickness 0.15)
				)
				(justify left bottom)
			)
		)
		(property "Value" "R_220R_0402"
			(at -1.011843 1.772047 90)
			(layer "F.Fab")
			(effects
				(font
					(size 0.7 0.7)
					(thickness 0.15)
				)
				(justify left bottom)
			)
		)
		(property "Datasheet" "https://www.bourns.com/docs/product-datasheets/cr.pdf"
			(at 0 0 90)
			(layer "F.Fab")
			(hide yes)
			(effects
				(font
					(size 1.27 1.27)
					(thickness 0.15)
				)
			)
		)
		(property "Author" "Antmicro"
			(at 274.860773 -120.556447 0)
			(layer "F.Fab")
			(hide yes)
			(effects
				(font
					(size 1 1)
					(thickness 0.15)
				)
			)
		)
		(property "License" "Apache-2.0"
			(at 274.860773 -120.556447 0)
			(layer "F.Fab")
			(hide yes)
			(effects
				(font
					(size 1 1)
					(thickness 0.15)
				)
			)
		)
		(property "MPN" "CR0402-FX-2200GLF"
			(at 274.860773 -120.556447 0)
			(layer "F.Fab")
			(hide yes)
			(effects
				(font
					(size 1 1)
					(thickness 0.15)
				)
			)
		)
		(property "Manufacturer" "Bourns"
			(at 274.860773 -120.556447 0)
			(layer "F.Fab")
			(hide yes)
			(effects
				(font
					(size 1 1)
					(thickness 0.15)
				)
			)
		)
		(property "Public" "False"
			(at 274.860773 -120.556447 0)
			(layer "F.Fab")
			(hide yes)
			(effects
				(font
					(size 1 1)
					(thickness 0.15)
				)
			)
		)
		(property "Tolerance" "1%"
			(at 274.860773 -120.556447 0)
			(layer "F.Fab")
			(hide yes)
			(effects
				(font
					(size 1 1)
					(thickness 0.15)
				)
			)
		)
		(property "Val" "220R"
			(at 274.860773 -120.556447 0)
			(layer "F.Fab")
			(hide yes)
			(effects
				(font
					(size 1 1)
					(thickness 0.15)
				)
			)
		)
		(sheetname "Power")
		(sheetfile "power.kicad_sch")
		(attr smd)
		(fp_rect
			(start -0.925 -0.47)
			(end 0.925 0.47)
			(stroke
				(width 0.05)
				(type default)
			)
			(fill no)
			(layer "F.CrtYd")
		)
		(fp_rect
			(start -0.5 -0.25)
			(end 0.5 0.25)
			(stroke
				(width 0.15)
				(type solid)
			)
			(fill no)
			(layer "F.Fab")
		)
		(pad "1" smd roundrect
			(at -0.48 0 90)
			(size 0.59 0.64)
			(layers "F.Cu" "F.Mask" "F.Paste")
			(roundrect_rratio 0.25)
			(net 1 "GND")
			(pintype "passive")
			(teardrops
				(best_length_ratio 0.2)
				(max_length 1)
				(best_width_ratio 0.9)
				(max_width 2)
				(curved_edges yes)
				(filter_ratio 0.9)
				(enabled yes)
				(allow_two_segments yes)
				(prefer_zone_connections yes)
			)
		)
		(pad "2" smd roundrect
			(at 0.48 0 90)
			(size 0.59 0.64)
			(layers "F.Cu" "F.Mask" "F.Paste")
			(roundrect_rratio 0.25)
			(net 981 "Net-(D28-C)")
			(pintype "passive")
			(teardrops
				(best_length_ratio 0.2)
				(max_length 1)
				(best_width_ratio 0.9)
				(max_width 2)
				(curved_edges yes)
				(filter_ratio 0.9)
				(enabled yes)
				(allow_two_segments yes)
				(prefer_zone_connections yes)
			)
		)
	)
	(footprint "antmicro-footprints:C_0402_1005Metric"
		(layer "F.Cu")
		(at 244.8 132.354 90)
		(descr "Capacitor SMD 0402")
		(tags "capacitor SMD 0402")
		(property "Reference" "C206"
			(at -3.656 0.45 90)
			(layer "F.SilkS")
			(effects
				(font
					(size 0.7 0.7)
					(thickness 0.15)
				)
				(justify left bottom)
			)
		)
		(property "Value" "C_1u_0402"
			(at -1.022927 2.155213 90)
			(layer "F.Fab")
			(effects
				(font
					(size 0.7 0.7)
					(thickness 0.15)
				)
				(justify left bottom)
			)
		)
		(property "Datasheet" "https://product.tdk.com/en/search/capacitor/ceramic/mlcc/info?part_no=C1005X6S1A105K050BC"
			(at 0 0 90)
			(layer "F.Fab")
			(hide yes)
			(effects
				(font
					(size 1.27 1.27)
					(thickness 0.15)
				)
			)
		)
		(property "Author" "Antmicro"
			(at 377.154 -112.446 0)
			(layer "F.Fab")
			(hide yes)
			(effects
				(font
					(size 1 1)
					(thickness 0.15)
				)
			)
		)
		(property "Dielectric" ""
			(at 377.154 -112.446 0)
			(layer "F.Fab")
			(hide yes)
			(effects
				(font
					(size 1 1)
					(thickness 0.15)
				)
			)
		)
		(property "License" "Apache-2.0"
			(at 377.154 -112.446 0)
			(layer "F.Fab")
			(hide yes)
			(effects
				(font
					(size 1 1)
					(thickness 0.15)
				)
			)
		)
		(property "MPN" "C1005X6S1A105K050BC"
			(at 377.154 -112.446 0)
			(layer "F.Fab")
			(hide yes)
			(effects
				(font
					(size 1 1)
					(thickness 0.15)
				)
			)
		)
		(property "Manufacturer" "TDK"
			(at 377.154 -112.446 0)
			(layer "F.Fab")
			(hide yes)
			(effects
				(font
					(size 1 1)
					(thickness 0.15)
				)
			)
		)
		(property "Public" "False"
			(at 377.154 -112.446 0)
			(layer "F.Fab")
			(hide yes)
			(effects
				(font
					(size 1 1)
					(thickness 0.15)
				)
			)
		)
		(property "Val" "1u"
			(at 377.154 -112.446 0)
			(layer "F.Fab")
			(hide yes)
			(effects
				(font
					(size 1 1)
					(thickness 0.15)
				)
			)
		)
		(property "Voltage" ""
			(at 377.154 -112.446 0)
			(layer "F.Fab")
			(hide yes)
			(effects
				(font
					(size 1 1)
					(thickness 0.15)
				)
			)
		)
		(sheetname "Com Express 7 MGMT")
		(sheetfile "com_express_7_mgmt.kicad_sch")
		(attr smd)
		(fp_rect
			(start -0.925 -0.47)
			(end 0.925 0.47)
			(stroke
				(width 0.05)
				(type default)
			)
			(fill no)
			(layer "F.CrtYd")
		)
		(fp_line
			(start 0.504 -0.25)
			(end 0.504 0.248)
			(stroke
				(width 0.15)
				(type solid)
			)
			(layer "F.Fab")
		)
		(fp_line
			(start -0.494 -0.25)
			(end 0.504 -0.25)
			(stroke
				(width 0.15)
				(type solid)
			)
			(layer "F.Fab")
		)
		(fp_line
			(start 0.504 0.248)
			(end -0.494 0.248)
			(stroke
				(width 0.15)
				(type solid)
			)
			(layer "F.Fab")
		)
		(fp_line
			(start -0.494 0.248)
			(end -0.494 -0.25)
			(stroke
				(width 0.15)
				(type solid)
			)
			(layer "F.Fab")
		)
		(pad "1" smd roundrect
			(at -0.48 0 90)
			(size 0.59 0.64)
			(layers "F.Cu" "F.Mask" "F.Paste")
			(roundrect_rratio 0.25)
			(net 1 "GND")
			(pintype "passive")
			(teardrops
				(best_length_ratio 0.2)
				(max_length 1)
				(best_width_ratio 0.9)
				(max_width 2)
				(curved_edges yes)
				(filter_ratio 0.9)
				(enabled yes)
				(allow_two_segments yes)
				(prefer_zone_connections yes)
			)
		)
		(pad "2" smd roundrect
			(at 0.48 0 90)
			(size 0.59 0.64)
			(layers "F.Cu" "F.Mask" "F.Paste")
			(roundrect_rratio 0.25)
			(net 46 "Net-(U34-OFFT)")
			(pintype "passive")
			(teardrops
				(best_length_ratio 0.2)
				(max_length 1)
				(best_width_ratio 0.9)
				(max_width 2)
				(curved_edges yes)
				(filter_ratio 0.9)
				(enabled yes)
				(allow_two_segments yes)
				(prefer_zone_connections yes)
			)
		)
	)
	(footprint "antmicro-footprints:C_0402_1005Metric"
		(layer "F.Cu")
		(at 310.2895 94.351 180)
		(descr "Capacitor SMD 0402")
		(tags "capacitor SMD 0402")
		(property "Reference" "C62"
			(at 0.8395 -0.409 0)
			(layer "F.SilkS")
			(effects
				(font
					(size 0.7 0.7)
					(thickness 0.15)
				)
				(justify right bottom)
			)
		)
		(property "Value" "C_1u_0402"
			(at -1.022927 2.155213 0)
			(layer "F.Fab")
			(effects
				(font
					(size 0.7 0.7)
					(thickness 0.15)
				)
				(justify right bottom)
			)
		)
		(property "Datasheet" "https://product.tdk.com/en/search/capacitor/ceramic/mlcc/info?part_no=C1005X6S1A105K050BC"
			(at 0 0 180)
			(layer "F.Fab")
			(hide yes)
			(effects
				(font
					(size 1.27 1.27)
					(thickness 0.15)
				)
			)
		)
		(property "Author" "Antmicro"
			(at 620.579 188.702 0)
			(layer "F.Fab")
			(hide yes)
			(effects
				(font
					(size 1 1)
					(thickness 0.15)
				)
			)
		)
		(property "Dielectric" ""
			(at 620.579 188.702 0)
			(layer "F.Fab")
			(hide yes)
			(effects
				(font
					(size 1 1)
					(thickness 0.15)
				)
			)
		)
		(property "License" "Apache-2.0"
			(at 620.579 188.702 0)
			(layer "F.Fab")
			(hide yes)
			(effects
				(font
					(size 1 1)
					(thickness 0.15)
				)
			)
		)
		(property "MPN" "C1005X6S1A105K050BC"
			(at 620.579 188.702 0)
			(layer "F.Fab")
			(hide yes)
			(effects
				(font
					(size 1 1)
					(thickness 0.15)
				)
			)
		)
		(property "Manufacturer" "TDK"
			(at 620.579 188.702 0)
			(layer "F.Fab")
			(hide yes)
			(effects
				(font
					(size 1 1)
					(thickness 0.15)
				)
			)
		)
		(property "Public" "False"
			(at 620.579 188.702 0)
			(layer "F.Fab")
			(hide yes)
			(effects
				(font
					(size 1 1)
					(thickness 0.15)
				)
			)
		)
		(property "Val" "1u"
			(at 620.579 188.702 0)
			(layer "F.Fab")
			(hide yes)
			(effects
				(font
					(size 1 1)
					(thickness 0.15)
				)
			)
		)
		(property "Voltage" ""
			(at 620.579 188.702 0)
			(layer "F.Fab")
			(hide yes)
			(effects
				(font
					(size 1 1)
					(thickness 0.15)
				)
			)
		)
		(sheetname "Power")
		(sheetfile "power.kicad_sch")
		(attr smd)
		(fp_rect
			(start -0.925 -0.47)
			(end 0.925 0.47)
			(stroke
				(width 0.05)
				(type default)
			)
			(fill no)
			(layer "F.CrtYd")
		)
		(fp_line
			(start 0.504 0.248)
			(end -0.494 0.248)
			(stroke
				(width 0.15)
				(type solid)
			)
			(layer "F.Fab")
		)
		(fp_line
			(start 0.504 -0.25)
			(end 0.504 0.248)
			(stroke
				(width 0.15)
				(type solid)
			)
			(layer "F.Fab")
		)
		(fp_line
			(start -0.494 0.248)
			(end -0.494 -0.25)
			(stroke
				(width 0.15)
				(type solid)
			)
			(layer "F.Fab")
		)
		(fp_line
			(start -0.494 -0.25)
			(end 0.504 -0.25)
			(stroke
				(width 0.15)
				(type solid)
			)
			(layer "F.Fab")
		)
		(pad "1" smd roundrect
			(at -0.48 0 180)
			(size 0.59 0.64)
			(layers "F.Cu" "F.Mask" "F.Paste")
			(roundrect_rratio 0.25)
			(net 1 "GND")
			(pintype "passive")
			(teardrops
				(best_length_ratio 0.2)
				(max_length 1)
				(best_width_ratio 0.9)
				(max_width 2)
				(curved_edges yes)
				(filter_ratio 0.9)
				(enabled yes)
				(allow_two_segments yes)
				(prefer_zone_connections yes)
			)
		)
		(pad "2" smd roundrect
			(at 0.48 0 180)
			(size 0.59 0.64)
			(layers "F.Cu" "F.Mask" "F.Paste")
			(roundrect_rratio 0.25)
			(net 75 "Net-(U50-IN+)")
			(pintype "passive")
			(teardrops
				(best_length_ratio 0.2)
				(max_length 1)
				(best_width_ratio 0.9)
				(max_width 2)
				(curved_edges yes)
				(filter_ratio 0.9)
				(enabled yes)
				(allow_two_segments yes)
				(prefer_zone_connections yes)
			)
		)
	)
	(footprint "antmicro-footprints:R_0402_1005Metric"
		(layer "F.Cu")
		(at 115.4 150.36 -90)
		(descr "Resistor SMD 0402")
		(tags "resistor SMD 0402")
		(property "Reference" "R210"
			(at -0.46 -4.5 90)
			(layer "F.SilkS")
			(effects
				(font
					(size 0.7 0.7)
					(thickness 0.15)
				)
				(justify right bottom)
			)
		)
		(property "Value" "R_1k_0402"
			(at -1.011843 1.772047 90)
			(layer "F.Fab")
			(effects
				(font
					(size 0.7 0.7)
					(thickness 0.15)
				)
				(justify right bottom)
			)
		)
		(property "Datasheet" "https://www.bourns.com/docs/product-datasheets/cr.pdf"
			(at 0 0 270)
			(layer "F.Fab")
			(hide yes)
			(effects
				(font
					(size 1.27 1.27)
					(thickness 0.15)
				)
			)
		)
		(property "Author" "Antmicro"
			(at -34.96 265.76 0)
			(layer "F.Fab")
			(hide yes)
			(effects
				(font
					(size 1 1)
					(thickness 0.15)
				)
			)
		)
		(property "License" "Apache-2.0"
			(at -34.96 265.76 0)
			(layer "F.Fab")
			(hide yes)
			(effects
				(font
					(size 1 1)
					(thickness 0.15)
				)
			)
		)
		(property "MPN" "CR0402-FX-1001GLF"
			(at -34.96 265.76 0)
			(layer "F.Fab")
			(hide yes)
			(effects
				(font
					(size 1 1)
					(thickness 0.15)
				)
			)
		)
		(property "Manufacturer" "Bourns"
			(at -34.96 265.76 0)
			(layer "F.Fab")
			(hide yes)
			(effects
				(font
					(size 1 1)
					(thickness 0.15)
				)
			)
		)
		(property "Public" "False"
			(at -34.96 265.76 0)
			(layer "F.Fab")
			(hide yes)
			(effects
				(font
					(size 1 1)
					(thickness 0.15)
				)
			)
		)
		(property "Tolerance" "1%"
			(at -34.96 265.76 0)
			(layer "F.Fab")
			(hide yes)
			(effects
				(font
					(size 1 1)
					(thickness 0.15)
				)
			)
		)
		(property "Val" "1k"
			(at -34.96 265.76 0)
			(layer "F.Fab")
			(hide yes)
			(effects
				(font
					(size 1 1)
					(thickness 0.15)
				)
			)
		)
		(sheetname "PCIe redriver")
		(sheetfile "pcie_redriver.kicad_sch")
		(attr smd)
		(fp_rect
			(start -0.925 -0.47)
			(end 0.925 0.47)
			(stroke
				(width 0.05)
				(type default)
			)
			(fill no)
			(layer "F.CrtYd")
		)
		(fp_rect
			(start -0.5 -0.25)
			(end 0.5 0.25)
			(stroke
				(width 0.15)
				(type solid)
			)
			(fill no)
			(layer "F.Fab")
		)
		(pad "1" smd roundrect
			(at -0.48 0 270)
			(size 0.59 0.64)
			(layers "F.Cu" "F.Mask" "F.Paste")
			(roundrect_rratio 0.25)
			(net 2 "+3V3")
			(pintype "passive")
			(teardrops
				(best_length_ratio 0.2)
				(max_length 1)
				(best_width_ratio 0.9)
				(max_width 2)
				(curved_edges yes)
				(filter_ratio 0.9)
				(enabled yes)
				(allow_two_segments yes)
				(prefer_zone_connections yes)
			)
		)
		(pad "2" smd roundrect
			(at 0.48 0 270)
			(size 0.59 0.64)
			(layers "F.Cu" "F.Mask" "F.Paste")
			(roundrect_rratio 0.25)
			(net 627 "/PCIe redriver/TX_FG1")
			(pintype "passive")
			(teardrops
				(best_length_ratio 0.2)
				(max_length 1)
				(best_width_ratio 0.9)
				(max_width 2)
				(curved_edges yes)
				(filter_ratio 0.9)
				(enabled yes)
				(allow_two_segments yes)
				(prefer_zone_connections yes)
			)
		)
	)
	(footprint "antmicro-footprints:R_0402_1005Metric"
		(layer "F.Cu")
		(at 252.670002 85.449999 180)
		(descr "Resistor SMD 0402")
		(tags "resistor SMD 0402")
		(property "Reference" "R154"
			(at 0.865 -0.440001 0)
			(layer "F.SilkS")
			(effects
				(font
					(size 0.7 0.7)
					(thickness 0.15)
				)
				(justify right bottom)
			)
		)
		(property "Value" "R_0R_0402"
			(at -1.011843 1.772047 0)
			(layer "F.Fab")
			(effects
				(font
					(size 0.7 0.7)
					(thickness 0.15)
				)
				(justify right bottom)
			)
		)
		(property "Datasheet" "https://industrial.panasonic.com/cdbs/www-data/pdf/RDA0000/AOA0000C301.pdf"
			(at 0 0 180)
			(layer "F.Fab")
			(hide yes)
			(effects
				(font
					(size 1.27 1.27)
					(thickness 0.15)
				)
			)
		)
		(property "Author" "Antmicro"
			(at 505.340004 170.899998 0)
			(layer "F.Fab")
			(hide yes)
			(effects
				(font
					(size 1 1)
					(thickness 0.15)
				)
			)
		)
		(property "Current" "1A"
			(at 505.340004 170.899998 0)
			(layer "F.Fab")
			(hide yes)
			(effects
				(font
					(size 1 1)
					(thickness 0.15)
				)
			)
		)
		(property "License" "Apache-2.0"
			(at 505.340004 170.899998 0)
			(layer "F.Fab")
			(hide yes)
			(effects
				(font
					(size 1 1)
					(thickness 0.15)
				)
			)
		)
		(property "MPN" "ERJ2GE0R00X"
			(at 505.340004 170.899998 0)
			(layer "F.Fab")
			(hide yes)
			(effects
				(font
					(size 1 1)
					(thickness 0.15)
				)
			)
		)
		(property "Manufacturer" "Panasonic"
			(at 505.340004 170.899998 0)
			(layer "F.Fab")
			(hide yes)
			(effects
				(font
					(size 1 1)
					(thickness 0.15)
				)
			)
		)
		(property "Public" "False"
			(at 505.340004 170.899998 0)
			(layer "F.Fab")
			(hide yes)
			(effects
				(font
					(size 1 1)
					(thickness 0.15)
				)
			)
		)
		(property "Tolerance" ""
			(at 505.340004 170.899998 0)
			(layer "F.Fab")
			(hide yes)
			(effects
				(font
					(size 1 1)
					(thickness 0.15)
				)
			)
		)
		(property "Val" "0R"
			(at 505.340004 170.899998 0)
			(layer "F.Fab")
			(hide yes)
			(effects
				(font
					(size 1 1)
					(thickness 0.15)
				)
			)
		)
		(sheetname "Misc")
		(sheetfile "misc.kicad_sch")
		(attr smd)
		(fp_rect
			(start -0.925 -0.47)
			(end 0.925 0.47)
			(stroke
				(width 0.05)
				(type default)
			)
			(fill no)
			(layer "F.CrtYd")
		)
		(fp_rect
			(start -0.5 -0.25)
			(end 0.5 0.25)
			(stroke
				(width 0.15)
				(type solid)
			)
			(fill no)
			(layer "F.Fab")
		)
		(pad "1" smd roundrect
			(at -0.48 0 180)
			(size 0.59 0.64)
			(layers "F.Cu" "F.Mask" "F.Paste")
			(roundrect_rratio 0.25)
			(net 594 "Net-(U24-GPIO4)")
			(pintype "passive")
			(teardrops
				(best_length_ratio 0.2)
				(max_length 1)
				(best_width_ratio 0.9)
				(max_width 2)
				(curved_edges yes)
				(filter_ratio 0.9)
				(enabled yes)
				(allow_two_segments yes)
				(prefer_zone_connections yes)
			)
		)
		(pad "2" smd roundrect
			(at 0.48 0 180)
			(size 0.59 0.64)
			(layers "F.Cu" "F.Mask" "F.Paste")
			(roundrect_rratio 0.25)
			(net 595 "/Misc/PWM_{SRCSEL}")
			(pintype "passive")
			(teardrops
				(best_length_ratio 0.2)
				(max_length 1)
				(best_width_ratio 0.9)
				(max_width 2)
				(curved_edges yes)
				(filter_ratio 0.9)
				(enabled yes)
				(allow_two_segments yes)
				(prefer_zone_connections yes)
			)
		)
	)
)
